# T6G (Grand Teton) — schematic netlist excerpt (pin names and nets, part order shuffled) for the footprints in the layout excerpt that follows; sources: Cadence DE-HDL packaged netlist, KiCad conversion of 04192023_DAF0TMB3IC0_F0TG_MB_C_brd_V02_OCP.brd

PR163  Q_RES  49.9 1% CHIP  pkg 0402LF  page 210 : A = PVDDCR_SOC_P1 ; B = VSENSE_PVDDCR_SOC_P1_DP
R1272  Q_RES  0 5% CHIP  pkg 0402LF  page 357 : A = SMB_INA230_8_3V3AUX_SCL_R ; B = SMB_INA230_8_3V3AUX_SCL_R1

(kicad_pcb
	(version 20260206)
	(generator "pcbnew")
	(generator_version "10.0")
	(general
		(thickness 1.6)
		(legacy_teardrops no)
	)
	(paper "A4")
	(title_block
		(title "04192023_DAF0TMB3IC0_F0TG_MB_C_brd_V02_OCP.brd")
		(comment 1 "Grand Teton / footprints 835-836 of 8354")
	)
	(layers
		(0 "F.Cu" signal "TOP")
		(4 "In1.Cu" signal "GND")
		(6 "In2.Cu" signal "IN1")
		(8 "In3.Cu" signal "GND1")
		(10 "In4.Cu" signal "IN2")
		(12 "In5.Cu" signal "GND2")
		(14 "In6.Cu" signal "IN3")
		(16 "In7.Cu" signal "GND3")
		(18 "In8.Cu" signal "VCC")
		(20 "In9.Cu" signal "VCC1")
		(22 "In10.Cu" signal "GND4")
		(24 "In11.Cu" signal "IN4")
		(26 "In12.Cu" signal "GND5")
		(28 "In13.Cu" signal "IN5")
		(30 "In14.Cu" signal "GND6")
		(32 "In15.Cu" signal "IN6")
		(34 "In16.Cu" signal "GND7")
		(2 "B.Cu" signal "BOTTOM")
		(9 "F.Adhes" user "F.Adhesive")
		(11 "B.Adhes" user "B.Adhesive")
		(13 "F.Paste" user "Package Geometry/Pastemask Top")
		(15 "B.Paste" user "Package Geometry/Pastemask Bottom")
		(5 "F.SilkS" user "Ref Des/Silkscreen Top")
		(7 "B.SilkS" user "Ref Des/Silkscreen Bottom")
		(1 "F.Mask" user "Board Geometry/Soldermask Top")
		(3 "B.Mask" user "Board Geometry/Soldermask Bottom")
		(17 "Dwgs.User" user "User.Drawings")
		(19 "Cmts.User" user "User.Comments")
		(21 "Eco1.User" user "User.Eco1")
		(23 "Eco2.User" user "User.Eco2")
		(25 "Edge.Cuts" user "Board Geometry/Outline")
		(27 "Margin" user)
		(31 "F.CrtYd" user "Package Geometry/Place Bound Top")
		(29 "B.CrtYd" user "Package Geometry/Place Bound Bottom")
		(35 "F.Fab" user "Ref Des/Assembly Top")
		(33 "B.Fab" user "Ref Des/Assembly Bottom")
	)
	(footprint ""
		(layer "F.Cu")
		(at 324.853046 -99.284536 180)
		(property "Reference" "R1272"
			(at 0 0 180)
			(layer "F.SilkS")
			(hide yes)
			(effects
				(font
					(size 1.27 1.27)
				)
			)
		)
		(property "Value" ""
			(at 0 0 180)
			(layer "F.Fab")
			(effects
				(font
					(size 1.27 1.27)
				)
			)
		)
		(duplicate_pad_numbers_are_jumpers no)
		(fp_line
			(start 0.7874 0.4064)
			(end -0.7874 0.4064)
			(stroke
				(width 0.1524)
				(type default)
			)
			(layer "F.SilkS")
		)
		(fp_line
			(start 0.7874 -0.4064)
			(end 0.7874 0.4064)
			(stroke
				(width 0.1524)
				(type default)
			)
			(layer "F.SilkS")
		)
		(fp_line
			(start -0.7874 0.4064)
			(end -0.7874 -0.4064)
			(stroke
				(width 0.1524)
				(type default)
			)
			(layer "F.SilkS")
		)
		(fp_line
			(start -0.7874 -0.4064)
			(end 0.7874 -0.4064)
			(stroke
				(width 0.1524)
				(type default)
			)
			(layer "F.SilkS")
		)
		(fp_line
			(start 0.67945 0.3048)
			(end 0.120396 0.3048)
			(stroke
				(width 0.1)
				(type default)
			)
			(layer "F.Fab")
		)
		(fp_line
			(start 0.67945 -0.3048)
			(end 0.67945 0.3048)
			(stroke
				(width 0.1)
				(type default)
			)
			(layer "F.Fab")
		)
		(fp_line
			(start 0.12065 -0.2794)
			(end 0.12065 -0.3048)
			(stroke
				(width 0.1)
				(type default)
			)
			(layer "F.Fab")
		)
		(fp_line
			(start 0.12065 -0.3048)
			(end 0.67945 -0.3048)
			(stroke
				(width 0.1)
				(type default)
			)
			(layer "F.Fab")
		)
		(fp_line
			(start 0.120396 0.3048)
			(end 0.120396 0.2794)
			(stroke
				(width 0.1)
				(type default)
			)
			(layer "F.Fab")
		)
		(fp_line
			(start 0.120396 0.2794)
			(end -0.12065 0.2794)
			(stroke
				(width 0.1)
				(type default)
			)
			(layer "F.Fab")
		)
		(fp_line
			(start -0.12065 0.3048)
			(end -0.67945 0.3048)
			(stroke
				(width 0.1)
				(type default)
			)
			(layer "F.Fab")
		)
		(fp_line
			(start -0.12065 0.2794)
			(end -0.12065 0.3048)
			(stroke
				(width 0.1)
				(type default)
			)
			(layer "F.Fab")
		)
		(fp_line
			(start -0.12065 -0.2794)
			(end 0.12065 -0.2794)
			(stroke
				(width 0.1)
				(type default)
			)
			(layer "F.Fab")
		)
		(fp_line
			(start -0.12065 -0.305054)
			(end -0.12065 -0.2794)
			(stroke
				(width 0.1)
				(type default)
			)
			(layer "F.Fab")
		)
		(fp_line
			(start -0.67945 0.3048)
			(end -0.67945 -0.305054)
			(stroke
				(width 0.1)
				(type default)
			)
			(layer "F.Fab")
		)
		(fp_line
			(start -0.67945 -0.305054)
			(end -0.12065 -0.305054)
			(stroke
				(width 0.1)
				(type default)
			)
			(layer "F.Fab")
		)
		(pad "1" smd circle
			(at -0.40005 0 180)
			(size 0 0)
			(layers "F.Cu" "F.Mask" "F.Paste")
			(net "SMB_INA230_8_3V3AUX_SCL_R")
		)
		(pad "2" smd circle
			(at 0.40005 0 180)
			(size 0 0)
			(layers "F.Cu" "F.Mask" "F.Paste")
			(net "SMB_INA230_8_3V3AUX_SCL_R1")
		)
	)
	(footprint ""
		(layer "F.Cu")
		(at 138.617198 -168.577006)
		(property "Reference" "PR163"
			(at 0 0 0)
			(layer "F.SilkS")
			(hide yes)
			(effects
				(font
					(size 1.27 1.27)
				)
			)
		)
		(property "Value" ""
			(at 0 0 0)
			(layer "F.Fab")
			(effects
				(font
					(size 1.27 1.27)
				)
			)
		)
		(duplicate_pad_numbers_are_jumpers no)
		(fp_line
			(start -0.7874 -0.4064)
			(end 0.7874 -0.4064)
			(stroke
				(width 0.1524)
				(type default)
			)
			(layer "F.SilkS")
		)
		(fp_line
			(start -0.7874 0.4064)
			(end -0.7874 -0.4064)
			(stroke
				(width 0.1524)
				(type default)
			)
			(layer "F.SilkS")
		)
		(fp_line
			(start 0.7874 -0.4064)
			(end 0.7874 0.4064)
			(stroke
				(width 0.1524)
				(type default)
			)
			(layer "F.SilkS")
		)
		(fp_line
			(start 0.7874 0.4064)
			(end -0.7874 0.4064)
			(stroke
				(width 0.1524)
				(type default)
			)
			(layer "F.SilkS")
		)
		(fp_line
			(start -0.67945 -0.305054)
			(end -0.12065 -0.305054)
			(stroke
				(width 0.1)
				(type default)
			)
			(layer "F.Fab")
		)
		(fp_line
			(start -0.67945 0.3048)
			(end -0.67945 -0.305054)
			(stroke
				(width 0.1)
				(type default)
			)
			(layer "F.Fab")
		)
		(fp_line
			(start -0.12065 -0.305054)
			(end -0.12065 -0.2794)
			(stroke
				(width 0.1)
				(type default)
			)
			(layer "F.Fab")
		)
		(fp_line
			(start -0.12065 -0.2794)
			(end 0.12065 -0.2794)
			(stroke
				(width 0.1)
				(type default)
			)
			(layer "F.Fab")
		)
		(fp_line
			(start -0.12065 0.2794)
			(end -0.12065 0.3048)
			(stroke
				(width 0.1)
				(type default)
			)
			(layer "F.Fab")
		)
		(fp_line
			(start -0.12065 0.3048)
			(end -0.67945 0.3048)
			(stroke
				(width 0.1)
				(type default)
			)
			(layer "F.Fab")
		)
		(fp_line
			(start 0.120396 0.2794)
			(end -0.12065 0.2794)
			(stroke
				(width 0.1)
				(type default)
			)
			(layer "F.Fab")
		)
		(fp_line
			(start 0.120396 0.3048)
			(end 0.120396 0.2794)
			(stroke
				(width 0.1)
				(type default)
			)
			(layer "F.Fab")
		)
		(fp_line
			(start 0.12065 -0.3048)
			(end 0.67945 -0.3048)
			(stroke
				(width 0.1)
				(type default)
			)
			(layer "F.Fab")
		)
		(fp_line
			(start 0.12065 -0.2794)
			(end 0.12065 -0.3048)
			(stroke
				(width 0.1)
				(type default)
			)
			(layer "F.Fab")
		)
		(fp_line
			(start 0.67945 -0.3048)
			(end 0.67945 0.3048)
			(stroke
				(width 0.1)
				(type default)
			)
			(layer "F.Fab")
		)
		(fp_line
			(start 0.67945 0.3048)
			(end 0.120396 0.3048)
			(stroke
				(width 0.1)
				(type default)
			)
			(layer "F.Fab")
		)
		(pad "1" smd circle
			(at -0.40005 0)
			(size 0 0)
			(layers "F.Cu" "F.Mask" "F.Paste")
			(net "PVDDCR_SOC_P1")
		)
		(pad "2" smd circle
			(at 0.40005 0)
			(size 0 0)
			(layers "F.Cu" "F.Mask" "F.Paste")
			(net "VSENSE_PVDDCR_SOC_P1_DP")
		)
	)
)
